(kicad_pcb
	(version 20241229)
	(generator "pcbnew")
	(generator_version "9.0")
	(general
		(thickness 1.61)
		(legacy_teardrops no)
	)
	(paper "A3")
	(title_block
		(title "SO-DIMM DDR5 Tester")
		(date "2025-11-26")
		(rev "1.3.0")
		(comment 9 "footprints 479-485 of 627")
	)
	(layers
		(0 "F.Cu" signal)
		(4 "In1.Cu" power)
		(6 "In2.Cu" mixed)
		(8 "In3.Cu" power)
		(10 "In4.Cu" mixed)
		(12 "In5.Cu" power)
		(14 "In6.Cu" mixed)
		(16 "In7.Cu" power)
		(18 "In8.Cu" power)
		(20 "In9.Cu" mixed)
		(22 "In10.Cu" power)
		(2 "B.Cu" signal)
		(9 "F.Adhes" user "F.Adhesive")
		(11 "B.Adhes" user "B.Adhesive")
		(13 "F.Paste" user)
		(15 "B.Paste" user)
		(5 "F.SilkS" user "F.Silkscreen")
		(7 "B.SilkS" user "B.Silkscreen")
		(1 "F.Mask" user)
		(3 "B.Mask" user)
		(17 "Dwgs.User" user "User.Drawings")
		(19 "Cmts.User" user "User.Comments")
		(21 "Eco1.User" user "User.Eco1")
		(23 "Eco2.User" user "User.Eco2")
		(25 "Edge.Cuts" user)
		(27 "Margin" user)
		(31 "F.CrtYd" user "F.Courtyard")
		(29 "B.CrtYd" user "B.Courtyard")
		(35 "F.Fab" user)
		(33 "B.Fab" user)
	)
	(footprint "antmicro-footprints:C_0402_1005Metric"
		(layer "B.Cu")
		(at 144.375501 182.801 -90)
		(descr "Capacitor SMD 0402 (1005 Metric), square (rectangular) end terminal, IPC_7351 nominal, (Body size source: IPC-SM-782 page 76, https://www.pcb-3d.com/wordpress/wp-content/uploads/ipc-sm-782a_amendment_1_and_2.pdf)")
		(tags "capacitor 0402")
		(property "Reference" "C45"
			(at 0 1.17 90)
			(layer "B.SilkS")
			(hide yes)
			(effects
				(font
					(size 0.7 0.7)
					(thickness 0.15)
				)
				(justify left bottom mirror)
			)
		)
		(property "Value" "C_100n_0402"
			(at 0 -1.169 90)
			(layer "B.Fab")
			(effects
				(font
					(size 0.7 0.7)
					(thickness 0.15)
				)
				(justify left bottom mirror)
			)
		)
		(property "Datasheet" "https://www.murata.com/products/productdetail?partno=GRM155R61H104KE14%23"
			(at 0 0 270)
			(layer "F.Fab")
			(hide yes)
			(effects
				(font
					(size 1.27 1.27)
					(thickness 0.15)
				)
			)
		)
		(property "Author" "Antmicro"
			(at -38.425499 327.176501 0)
			(layer "B.Fab")
			(hide yes)
			(effects
				(font
					(size 1 1)
					(thickness 0.15)
				)
				(justify mirror)
			)
		)
		(property "Dielectric" "X5R"
			(at -38.425499 327.176501 0)
			(layer "B.Fab")
			(hide yes)
			(effects
				(font
					(size 1 1)
					(thickness 0.15)
				)
				(justify mirror)
			)
		)
		(property "License" "Apache-2.0"
			(at -38.425499 327.176501 0)
			(layer "B.Fab")
			(hide yes)
			(effects
				(font
					(size 1 1)
					(thickness 0.15)
				)
				(justify mirror)
			)
		)
		(property "MPN" "GRM155R61H104KE14D"
			(at -38.425499 327.176501 0)
			(layer "B.Fab")
			(hide yes)
			(effects
				(font
					(size 1 1)
					(thickness 0.15)
				)
				(justify mirror)
			)
		)
		(property "Manufacturer" "Murata"
			(at -38.425499 327.176501 0)
			(layer "B.Fab")
			(hide yes)
			(effects
				(font
					(size 1 1)
					(thickness 0.15)
				)
				(justify mirror)
			)
		)
		(property "Val" "100n"
			(at -38.425499 327.176501 0)
			(layer "B.Fab")
			(hide yes)
			(effects
				(font
					(size 1 1)
					(thickness 0.15)
				)
				(justify mirror)
			)
		)
		(property "Voltage" "50V"
			(at -38.425499 327.176501 0)
			(layer "B.Fab")
			(hide yes)
			(effects
				(font
					(size 1 1)
					(thickness 0.15)
				)
				(justify mirror)
			)
		)
		(sheetname "/FPGA power/")
		(sheetfile "fpga-power.kicad_sch")
		(attr smd)
		(fp_rect
			(start -0.9656 0.4572)
			(end 0.9652 -0.4828)
			(stroke
				(width 0.05)
				(type solid)
			)
			(fill no)
			(layer "B.CrtYd")
		)
		(fp_line
			(start -0.5 0.25)
			(end 0.498 0.25)
			(stroke
				(width 0.15)
				(type solid)
			)
			(layer "B.Fab")
		)
		(fp_line
			(start 0.498 0.25)
			(end 0.498 -0.248)
			(stroke
				(width 0.15)
				(type solid)
			)
			(layer "B.Fab")
		)
		(fp_line
			(start -0.5 -0.248)
			(end -0.5 0.25)
			(stroke
				(width 0.15)
				(type solid)
			)
			(layer "B.Fab")
		)
		(fp_line
			(start 0.498 -0.248)
			(end -0.5 -0.248)
			(stroke
				(width 0.15)
				(type solid)
			)
			(layer "B.Fab")
		)
		(pad "1" smd roundrect
			(at -0.5 0 180)
			(size 0.6 0.6)
			(layers "B.Cu" "B.Mask" "B.Paste")
			(roundrect_rratio 0.25)
			(net 1 "GND")
			(pintype "passive")
		)
		(pad "2" smd roundrect
			(at 0.498 0 270)
			(size 0.6 0.6)
			(layers "B.Cu" "B.Mask" "B.Paste")
			(roundrect_rratio 0.25)
			(net 200 "+3V3")
			(pintype "passive")
		)
	)
	(footprint "antmicro-footprints:C_0402_1005Metric"
		(layer "B.Cu")
		(at 146.375001 178.8005 90)
		(descr "Capacitor SMD 0402 (1005 Metric), square (rectangular) end terminal, IPC_7351 nominal, (Body size source: IPC-SM-782 page 76, https://www.pcb-3d.com/wordpress/wp-content/uploads/ipc-sm-782a_amendment_1_and_2.pdf)")
		(tags "capacitor 0402")
		(property "Reference" "C76"
			(at 0 1.17 270)
			(layer "B.SilkS")
			(hide yes)
			(effects
				(font
					(size 0.7 0.7)
					(thickness 0.15)
				)
				(justify left bottom mirror)
			)
		)
		(property "Value" "C_100n_0402"
			(at 0 -1.169 270)
			(layer "B.Fab")
			(effects
				(font
					(size 0.7 0.7)
					(thickness 0.15)
				)
				(justify left bottom mirror)
			)
		)
		(property "Datasheet" "https://www.murata.com/products/productdetail?partno=GRM155R61H104KE14%23"
			(at 0 0 90)
			(layer "F.Fab")
			(hide yes)
			(effects
				(font
					(size 1.27 1.27)
					(thickness 0.15)
				)
			)
		)
		(property "Author" "Antmicro"
			(at 325.175501 32.425499 0)
			(layer "B.Fab")
			(hide yes)
			(effects
				(font
					(size 1 1)
					(thickness 0.15)
				)
				(justify mirror)
			)
		)
		(property "Dielectric" "X5R"
			(at 325.175501 32.425499 0)
			(layer "B.Fab")
			(hide yes)
			(effects
				(font
					(size 1 1)
					(thickness 0.15)
				)
				(justify mirror)
			)
		)
		(property "License" "Apache-2.0"
			(at 325.175501 32.425499 0)
			(layer "B.Fab")
			(hide yes)
			(effects
				(font
					(size 1 1)
					(thickness 0.15)
				)
				(justify mirror)
			)
		)
		(property "MPN" "GRM155R61H104KE14D"
			(at 325.175501 32.425499 0)
			(layer "B.Fab")
			(hide yes)
			(effects
				(font
					(size 1 1)
					(thickness 0.15)
				)
				(justify mirror)
			)
		)
		(property "Manufacturer" "Murata"
			(at 325.175501 32.425499 0)
			(layer "B.Fab")
			(hide yes)
			(effects
				(font
					(size 1 1)
					(thickness 0.15)
				)
				(justify mirror)
			)
		)
		(property "Val" "100n"
			(at 325.175501 32.425499 0)
			(layer "B.Fab")
			(hide yes)
			(effects
				(font
					(size 1 1)
					(thickness 0.15)
				)
				(justify mirror)
			)
		)
		(property "Voltage" "50V"
			(at 325.175501 32.425499 0)
			(layer "B.Fab")
			(hide yes)
			(effects
				(font
					(size 1 1)
					(thickness 0.15)
				)
				(justify mirror)
			)
		)
		(sheetname "/FPGA power/")
		(sheetfile "fpga-power.kicad_sch")
		(attr smd)
		(fp_rect
			(start -0.9656 0.4572)
			(end 0.9652 -0.4828)
			(stroke
				(width 0.05)
				(type solid)
			)
			(fill no)
			(layer "B.CrtYd")
		)
		(fp_line
			(start 0.498 -0.248)
			(end -0.5 -0.248)
			(stroke
				(width 0.15)
				(type solid)
			)
			(layer "B.Fab")
		)
		(fp_line
			(start -0.5 -0.248)
			(end -0.5 0.25)
			(stroke
				(width 0.15)
				(type solid)
			)
			(layer "B.Fab")
		)
		(fp_line
			(start 0.498 0.25)
			(end 0.498 -0.248)
			(stroke
				(width 0.15)
				(type solid)
			)
			(layer "B.Fab")
		)
		(fp_line
			(start -0.5 0.25)
			(end 0.498 0.25)
			(stroke
				(width 0.15)
				(type solid)
			)
			(layer "B.Fab")
		)
		(pad "1" smd roundrect
			(at -0.5 0)
			(size 0.6 0.6)
			(layers "B.Cu" "B.Mask" "B.Paste")
			(roundrect_rratio 0.25)
			(net 1 "GND")
			(pintype "passive")
		)
		(pad "2" smd roundrect
			(at 0.498 0 90)
			(size 0.6 0.6)
			(layers "B.Cu" "B.Mask" "B.Paste")
			(roundrect_rratio 0.25)
			(net 200 "+3V3")
			(pintype "passive")
		)
	)
	(footprint "antmicro-footprints:TP_SMD_1mm"
		(layer "B.Cu")
		(at 186.94 160.03 180)
		(property "Reference" "TP33"
			(at 0 0.731898 0)
			(layer "B.SilkS")
			(hide yes)
			(effects
				(font
					(size 0.7 0.7)
					(thickness 0.15)
				)
				(justify left bottom mirror)
			)
		)
		(property "Value" "TP_1mm_SMD"
			(at 0 -1.4 0)
			(layer "B.Fab")
			(effects
				(font
					(size 0.7 0.7)
					(thickness 0.15)
				)
				(justify left bottom mirror)
			)
		)
		(property "MPN" ""
			(at 0 0 0)
			(unlocked yes)
			(layer "B.Fab")
			(hide yes)
			(effects
				(font
					(size 1 1)
					(thickness 0.15)
				)
				(justify mirror)
			)
		)
		(property "Manufacturer" ""
			(at 0 0 0)
			(unlocked yes)
			(layer "B.Fab")
			(hide yes)
			(effects
				(font
					(size 1 1)
					(thickness 0.15)
				)
				(justify mirror)
			)
		)
		(property "Author" "Antmicro"
			(at 0 0 0)
			(unlocked yes)
			(layer "B.Fab")
			(hide yes)
			(effects
				(font
					(size 1 1)
					(thickness 0.15)
				)
				(justify mirror)
			)
		)
		(property "License" "Apache-2.0"
			(at 0 0 0)
			(unlocked yes)
			(layer "B.Fab")
			(hide yes)
			(effects
				(font
					(size 1 1)
					(thickness 0.15)
				)
				(justify mirror)
			)
		)
		(sheetname "/Supply/")
		(sheetfile "supply.kicad_sch")
		(attr exclude_from_pos_files)
		(fp_circle
			(center 0 0)
			(end 0.6 0)
			(stroke
				(width 0.05)
				(type default)
			)
			(fill no)
			(layer "B.CrtYd")
		)
		(fp_text user "${REFERENCE}"
			(at -0.5 -2.8 0)
			(layer "B.Fab")
			(effects
				(font
					(size 0.7 0.7)
					(thickness 0.15)
				)
				(justify left bottom mirror)
			)
		)
		(fp_text user "Author: Antmicro"
			(at -0.5 -4 0)
			(layer "B.Fab")
			(effects
				(font
					(size 0.7 0.7)
					(thickness 0.15)
				)
				(justify left bottom mirror)
			)
		)
		(fp_text user "License: Apache-2.0"
			(at -0.5 -5.2 0)
			(layer "B.Fab")
			(effects
				(font
					(size 0.7 0.7)
					(thickness 0.15)
				)
				(justify left bottom mirror)
			)
		)
		(pad "1" smd circle
			(at 0 0 180)
			(size 1 1)
			(layers "B.Cu" "B.Mask")
			(net 206 "+1V1")
			(pinfunction "1")
			(pintype "passive")
		)
	)
	(footprint "antmicro-footprints:C_0402_1005Metric"
		(layer "B.Cu")
		(at 138.877001 173.3025 180)
		(descr "Capacitor SMD 0402 (1005 Metric), square (rectangular) end terminal, IPC_7351 nominal, (Body size source: IPC-SM-782 page 76, https://www.pcb-3d.com/wordpress/wp-content/uploads/ipc-sm-782a_amendment_1_and_2.pdf)")
		(tags "capacitor 0402")
		(property "Reference" "C75"
			(at 0 1.17 0)
			(layer "B.SilkS")
			(hide yes)
			(effects
				(font
					(size 0.7 0.7)
					(thickness 0.15)
				)
				(justify left bottom mirror)
			)
		)
		(property "Value" "C_100n_0402"
			(at 0 -1.169 0)
			(layer "B.Fab")
			(effects
				(font
					(size 0.7 0.7)
					(thickness 0.15)
				)
				(justify left bottom mirror)
			)
		)
		(property "Datasheet" "https://www.murata.com/products/productdetail?partno=GRM155R61H104KE14%23"
			(at 0 0 180)
			(layer "F.Fab")
			(hide yes)
			(effects
				(font
					(size 1.27 1.27)
					(thickness 0.15)
				)
			)
		)
		(property "Author" "Antmicro"
			(at 277.754002 346.605 0)
			(layer "B.Fab")
			(hide yes)
			(effects
				(font
					(size 1 1)
					(thickness 0.15)
				)
				(justify mirror)
			)
		)
		(property "Dielectric" "X5R"
			(at 277.754002 346.605 0)
			(layer "B.Fab")
			(hide yes)
			(effects
				(font
					(size 1 1)
					(thickness 0.15)
				)
				(justify mirror)
			)
		)
		(property "License" "Apache-2.0"
			(at 277.754002 346.605 0)
			(layer "B.Fab")
			(hide yes)
			(effects
				(font
					(size 1 1)
					(thickness 0.15)
				)
				(justify mirror)
			)
		)
		(property "MPN" "GRM155R61H104KE14D"
			(at 277.754002 346.605 0)
			(layer "B.Fab")
			(hide yes)
			(effects
				(font
					(size 1 1)
					(thickness 0.15)
				)
				(justify mirror)
			)
		)
		(property "Manufacturer" "Murata"
			(at 277.754002 346.605 0)
			(layer "B.Fab")
			(hide yes)
			(effects
				(font
					(size 1 1)
					(thickness 0.15)
				)
				(justify mirror)
			)
		)
		(property "Val" "100n"
			(at 277.754002 346.605 0)
			(layer "B.Fab")
			(hide yes)
			(effects
				(font
					(size 1 1)
					(thickness 0.15)
				)
				(justify mirror)
			)
		)
		(property "Voltage" "50V"
			(at 277.754002 346.605 0)
			(layer "B.Fab")
			(hide yes)
			(effects
				(font
					(size 1 1)
					(thickness 0.15)
				)
				(justify mirror)
			)
		)
		(sheetname "/FPGA power/")
		(sheetfile "fpga-power.kicad_sch")
		(attr smd)
		(fp_rect
			(start -0.9656 0.4572)
			(end 0.9652 -0.4828)
			(stroke
				(width 0.05)
				(type solid)
			)
			(fill no)
			(layer "B.CrtYd")
		)
		(fp_line
			(start 0.498 0.25)
			(end 0.498 -0.248)
			(stroke
				(width 0.15)
				(type solid)
			)
			(layer "B.Fab")
		)
		(fp_line
			(start 0.498 -0.248)
			(end -0.5 -0.248)
			(stroke
				(width 0.15)
				(type solid)
			)
			(layer "B.Fab")
		)
		(fp_line
			(start -0.5 0.25)
			(end 0.498 0.25)
			(stroke
				(width 0.15)
				(type solid)
			)
			(layer "B.Fab")
		)
		(fp_line
			(start -0.5 -0.248)
			(end -0.5 0.25)
			(stroke
				(width 0.15)
				(type solid)
			)
			(layer "B.Fab")
		)
		(pad "1" smd roundrect
			(at -0.5 0 90)
			(size 0.6 0.6)
			(layers "B.Cu" "B.Mask" "B.Paste")
			(roundrect_rratio 0.25)
			(net 1 "GND")
			(pintype "passive")
		)
		(pad "2" smd roundrect
			(at 0.498 0 180)
			(size 0.6 0.6)
			(layers "B.Cu" "B.Mask" "B.Paste")
			(roundrect_rratio 0.25)
			(net 227 "+1V0")
			(pintype "passive")
		)
	)
	(footprint "antmicro-footprints:R_0402_1005Metric"
		(layer "B.Cu")
		(at 123.7 187.85 90)
		(descr "Resistor SMD 0402")
		(tags "resistor SMD 0402")
		(property "Reference" "R21"
			(at -0.85 0.35 270)
			(layer "B.SilkS")
			(effects
				(font
					(size 0.7 0.7)
					(thickness 0.15)
				)
				(justify left bottom mirror)
			)
		)
		(property "Value" "R_100R_0402"
			(at -1.011843 -1.772047 270)
			(layer "B.Fab")
			(effects
				(font
					(size 0.7 0.7)
					(thickness 0.15)
				)
				(justify left bottom mirror)
			)
		)
		(property "Datasheet" "https://www.bourns.com/docs/product-datasheets/cr.pdf"
			(at 0 0 90)
			(layer "F.Fab")
			(hide yes)
			(effects
				(font
					(size 1.27 1.27)
					(thickness 0.15)
				)
			)
		)
		(property "Author" "Antmicro"
			(at 311.55 64.15 0)
			(layer "B.Fab")
			(hide yes)
			(effects
				(font
					(size 1 1)
					(thickness 0.15)
				)
				(justify mirror)
			)
		)
		(property "License" "Apache-2.0"
			(at 311.55 64.15 0)
			(layer "B.Fab")
			(hide yes)
			(effects
				(font
					(size 1 1)
					(thickness 0.15)
				)
				(justify mirror)
			)
		)
		(property "MPN" "CR0402-FX-1000GLF"
			(at 311.55 64.15 0)
			(layer "B.Fab")
			(hide yes)
			(effects
				(font
					(size 1 1)
					(thickness 0.15)
				)
				(justify mirror)
			)
		)
		(property "Manufacturer" "Bourns"
			(at 311.55 64.15 0)
			(layer "B.Fab")
			(hide yes)
			(effects
				(font
					(size 1 1)
					(thickness 0.15)
				)
				(justify mirror)
			)
		)
		(property "Tolerance" "1%"
			(at 311.55 64.15 0)
			(layer "B.Fab")
			(hide yes)
			(effects
				(font
					(size 1 1)
					(thickness 0.15)
				)
				(justify mirror)
			)
		)
		(property "Val" "100R"
			(at 311.55 64.15 0)
			(layer "B.Fab")
			(hide yes)
			(effects
				(font
					(size 1 1)
					(thickness 0.15)
				)
				(justify mirror)
			)
		)
		(sheetname "/FPGA bank 14/")
		(sheetfile "fpga-bank-14.kicad_sch")
		(attr smd)
		(fp_rect
			(start -0.93 0.47)
			(end 0.93 -0.47)
			(stroke
				(width 0.05)
				(type solid)
			)
			(fill no)
			(layer "B.CrtYd")
		)
		(fp_rect
			(start -0.5 0.25)
			(end 0.5 -0.25)
			(stroke
				(width 0.15)
				(type solid)
			)
			(fill no)
			(layer "B.Fab")
		)
		(pad "1" smd roundrect
			(at -0.485 0 90)
			(size 0.59 0.64)
			(layers "B.Cu" "B.Mask" "B.Paste")
			(roundrect_rratio 0.25)
			(net 200 "+3V3")
			(pintype "passive")
		)
		(pad "2" smd roundrect
			(at 0.485 0 90)
			(size 0.59 0.64)
			(layers "B.Cu" "B.Mask" "B.Paste")
			(roundrect_rratio 0.25)
			(net 612 "/FPGA bank 14/PUDC_B")
			(pintype "passive")
		)
	)
	(footprint "antmicro-footprints:TP_SMD_1mm"
		(layer "B.Cu")
		(at 97.5 185.775 180)
		(property "Reference" "TP42"
			(at -3.2 -0.425 0)
			(layer "B.SilkS")
			(effects
				(font
					(size 0.7 0.7)
					(thickness 0.15)
				)
				(justify left bottom mirror)
			)
		)
		(property "Value" "TP_1mm_SMD"
			(at 0 -1.4 0)
			(layer "B.Fab")
			(effects
				(font
					(size 0.7 0.7)
					(thickness 0.15)
				)
				(justify left bottom mirror)
			)
		)
		(property "MPN" ""
			(at 0 0 0)
			(unlocked yes)
			(layer "B.Fab")
			(hide yes)
			(effects
				(font
					(size 1 1)
					(thickness 0.15)
				)
				(justify mirror)
			)
		)
		(property "Manufacturer" ""
			(at 0 0 0)
			(unlocked yes)
			(layer "B.Fab")
			(hide yes)
			(effects
				(font
					(size 1 1)
					(thickness 0.15)
				)
				(justify mirror)
			)
		)
		(property "Author" "Antmicro"
			(at 0 0 0)
			(unlocked yes)
			(layer "B.Fab")
			(hide yes)
			(effects
				(font
					(size 1 1)
					(thickness 0.15)
				)
				(justify mirror)
			)
		)
		(property "License" "Apache-2.0"
			(at 0 0 0)
			(unlocked yes)
			(layer "B.Fab")
			(hide yes)
			(effects
				(font
					(size 1 1)
					(thickness 0.15)
				)
				(justify mirror)
			)
		)
		(sheetname "/Debug FTDI/")
		(sheetfile "debug-ftdi.kicad_sch")
		(attr exclude_from_pos_files)
		(fp_circle
			(center 0 0)
			(end 0.6 0)
			(stroke
				(width 0.05)
				(type default)
			)
			(fill no)
			(layer "B.CrtYd")
		)
		(fp_text user "${REFERENCE}"
			(at -0.5 -2.8 0)
			(layer "B.Fab")
			(effects
				(font
					(size 0.7 0.7)
					(thickness 0.15)
				)
				(justify left bottom mirror)
			)
		)
		(fp_text user "License: Apache-2.0"
			(at -0.5 -5.2 0)
			(layer "B.Fab")
			(effects
				(font
					(size 0.7 0.7)
					(thickness 0.15)
				)
				(justify left bottom mirror)
			)
		)
		(fp_text user "Author: Antmicro"
			(at -0.5 -4 0)
			(layer "B.Fab")
			(effects
				(font
					(size 0.7 0.7)
					(thickness 0.15)
				)
				(justify left bottom mirror)
			)
		)
		(pad "1" smd circle
			(at 0 0 180)
			(size 1 1)
			(layers "B.Cu" "B.Mask")
			(net 45 "/Debug FTDI/JTAG.TMS")
			(pinfunction "1")
			(pintype "passive")
		)
	)
	(footprint "antmicro-footprints:TP_SMD_1mm"
		(layer "B.Cu")
		(at 186.5 137 180)
		(property "Reference" "TP25"
			(at 0 0.731898 0)
			(layer "B.SilkS")
			(hide yes)
			(effects
				(font
					(size 0.7 0.7)
					(thickness 0.15)
				)
				(justify left bottom mirror)
			)
		)
		(property "Value" "TP_1mm_SMD"
			(at 0 -1.4 0)
			(layer "B.Fab")
			(effects
				(font
					(size 0.7 0.7)
					(thickness 0.15)
				)
				(justify left bottom mirror)
			)
		)
		(property "MPN" ""
			(at 0 0 0)
			(unlocked yes)
			(layer "B.Fab")
			(hide yes)
			(effects
				(font
					(size 1 1)
					(thickness 0.15)
				)
				(justify mirror)
			)
		)
		(property "Manufacturer" ""
			(at 0 0 0)
			(unlocked yes)
			(layer "B.Fab")
			(hide yes)
			(effects
				(font
					(size 1 1)
					(thickness 0.15)
				)
				(justify mirror)
			)
		)
		(property "Author" "Antmicro"
			(at 0 0 0)
			(unlocked yes)
			(layer "B.Fab")
			(hide yes)
			(effects
				(font
					(size 1 1)
					(thickness 0.15)
				)
				(justify mirror)
			)
		)
		(property "License" "Apache-2.0"
			(at 0 0 0)
			(unlocked yes)
			(layer "B.Fab")
			(hide yes)
			(effects
				(font
					(size 1 1)
					(thickness 0.15)
				)
				(justify mirror)
			)
		)
		(sheetname "/Supply/")
		(sheetfile "supply.kicad_sch")
		(attr exclude_from_pos_files)
		(fp_circle
			(center 0 0)
			(end 0.6 0)
			(stroke
				(width 0.05)
				(type default)
			)
			(fill no)
			(layer "B.CrtYd")
		)
		(fp_text user "${REFERENCE}"
			(at -0.5 -2.8 0)
			(layer "B.Fab")
			(effects
				(font
					(size 0.7 0.7)
					(thickness 0.15)
				)
				(justify left bottom mirror)
			)
		)
		(fp_text user "License: Apache-2.0"
			(at -0.5 -5.2 0)
			(layer "B.Fab")
			(effects
				(font
					(size 0.7 0.7)
					(thickness 0.15)
				)
				(justify left bottom mirror)
			)
		)
		(fp_text user "Author: Antmicro"
			(at -0.5 -4 0)
			(layer "B.Fab")
			(effects
				(font
					(size 0.7 0.7)
					(thickness 0.15)
				)
				(justify left bottom mirror)
			)
		)
		(pad "1" smd circle
			(at 0 0 180)
			(size 1 1)
			(layers "B.Cu" "B.Mask")
			(net 38 "VDC")
			(pinfunction "1")
			(pintype "passive")
		)
	)
)
